# BASEBOARD_FAB2 (Tioga Pass) — schematic netlist excerpt (pin names and nets, part order shuffled) for the footprints in the layout excerpt that follows; sources: Cadence DE-HDL packaged netlist, KiCad conversion of Wiwynn_Tioga_Pass_MB.brd

R2U13  RES  2.26K 1.0% CHIP  pkg 0402  page 159 : A = P3V3_STBY ; B = SMB_OCP_FRU_STBY_LVC3_SDA_R
R9F3  RES  4.75K 1% CHIP  pkg 0402  page 170 : A = P3V3_STBY ; B = FM_FAST_PROCHOT_EN
R7D18  RES  1.00K 1% CHIP  pkg 0402  page 134 : A = FM_THERMTRIP_DLY ; B = FM_THERMTRIP_DLY_R

(kicad_pcb
	(version 20260206)
	(generator "pcbnew")
	(generator_version "10.0")
	(general
		(thickness 1.6)
		(legacy_teardrops no)
	)
	(paper "A4")
	(title_block
		(title "Wiwynn_Tioga_Pass_MB.brd")
		(comment 1 "Tioga Pass / footprints 2694-2696 of 4770")
	)
	(layers
		(0 "F.Cu" signal "TOP")
		(4 "In1.Cu" signal "L2GND")
		(6 "In2.Cu" signal "L3")
		(8 "In3.Cu" signal "L4GND")
		(10 "In4.Cu" signal "L5")
		(12 "In5.Cu" signal "L6GND")
		(14 "In6.Cu" signal "L7VCC")
		(16 "In7.Cu" signal "L8VCC")
		(18 "In8.Cu" signal "L9GND")
		(20 "In9.Cu" signal "L10")
		(22 "In10.Cu" signal "L11GND")
		(24 "In11.Cu" signal "L12")
		(26 "In12.Cu" signal "L13GND")
		(2 "B.Cu" signal "BOTTOM")
		(9 "F.Adhes" user "F.Adhesive")
		(11 "B.Adhes" user "B.Adhesive")
		(13 "F.Paste" user "Package Geometry/Pastemask Top")
		(15 "B.Paste" user "Package Geometry/Pastemask Bottom")
		(5 "F.SilkS" user "Ref Des/Silkscreen Top")
		(7 "B.SilkS" user "Ref Des/Silkscreen Bottom")
		(1 "F.Mask" user "Board Geometry/Soldermask Top")
		(3 "B.Mask" user "Board Geometry/Soldermask Bottom")
		(17 "Dwgs.User" user "User.Drawings")
		(19 "Cmts.User" user "User.Comments")
		(21 "Eco1.User" user "User.Eco1")
		(23 "Eco2.User" user "User.Eco2")
		(25 "Edge.Cuts" user "Board Geometry/Outline")
		(27 "Margin" user)
		(31 "F.CrtYd" user "Package Geometry/Place Bound Top")
		(29 "B.CrtYd" user "Package Geometry/Place Bound Bottom")
		(35 "F.Fab" user "Ref Des/Assembly Top")
		(33 "B.Fab" user "Ref Des/Assembly Bottom")
	)
	(footprint ""
		(layer "B.Cu")
		(at 401.5613 -37.1094 90)
		(property "Reference" "R2U13"
			(at 0 0 90)
			(layer "B.SilkS")
			(hide yes)
			(effects
				(font
					(size 1.27 1.27)
				)
				(justify mirror)
			)
		)
		(property "Value" ""
			(at 0 0 90)
			(layer "B.Fab")
			(effects
				(font
					(size 1.27 1.27)
				)
				(justify mirror)
			)
		)
		(duplicate_pad_numbers_are_jumpers no)
		(fp_poly
			(pts
				(xy 0.2794 -0.1016) (xy -0.2794 -0.1016) (xy -0.2794 0.9906) (xy 0.2794 0.9906)
			)
			(stroke
				(width 0)
				(type default)
			)
			(fill no)
			(layer "B.CrtYd")
		)
		(fp_line
			(start 0.2794 -0.1016)
			(end 0.2794 0.9906)
			(stroke
				(width 0.1)
				(type default)
			)
			(layer "B.Fab")
		)
		(fp_line
			(start -0.2794 -0.1016)
			(end 0.2794 -0.1016)
			(stroke
				(width 0.1)
				(type default)
			)
			(layer "B.Fab")
		)
		(fp_line
			(start 0.2794 0.9906)
			(end -0.2794 0.9906)
			(stroke
				(width 0.1)
				(type default)
			)
			(layer "B.Fab")
		)
		(fp_line
			(start -0.2794 0.9906)
			(end -0.2794 -0.1016)
			(stroke
				(width 0.1)
				(type default)
			)
			(layer "B.Fab")
		)
		(pad "1" smd rect
			(at 0 0 270)
			(size 0.508 0.508)
			(layers "B.Cu" "B.Mask" "B.Paste")
			(net "P3V3_STBY")
		)
		(pad "2" smd rect
			(at 0 0.889 270)
			(size 0.508 0.508)
			(layers "B.Cu" "B.Mask" "B.Paste")
			(net "SMB_OCP_FRU_STBY_LVC3_SDA_R")
		)
		(zone
			(layer "B.Cu")
			(hatch none 0.5)
			(connect_pads
				(clearance 0)
			)
			(min_thickness 0.25)
			(keepout
				(tracks allowed)
				(vias not_allowed)
				(pads allowed)
				(copperpour not_allowed)
				(footprints allowed)
			)
			(placement
				(enabled no)
				(sheetname "")
			)
			(fill
				(thermal_gap 0.5)
				(thermal_bridge_width 0.5)
				(island_removal_mode 0)
			)
			(polygon
				(pts
					(xy 401.8153 -37.3634) (xy 401.8153 -36.8554) (xy 402.1963 -36.8554) (xy 402.1963 -37.3634)
				)
			)
		)
		(zone
			(layer "B.Cu")
			(hatch none 0.5)
			(connect_pads
				(clearance 0)
			)
			(min_thickness 0.25)
			(keepout
				(tracks not_allowed)
				(vias allowed)
				(pads allowed)
				(copperpour not_allowed)
				(footprints allowed)
			)
			(placement
				(enabled no)
				(sheetname "")
			)
			(fill
				(thermal_gap 0.5)
				(thermal_bridge_width 0.5)
				(island_removal_mode 0)
			)
			(polygon
				(pts
					(xy 402.1963 -37.3634) (xy 402.1963 -36.8554) (xy 401.8153 -36.8554) (xy 401.8153 -37.3634)
				)
			)
		)
	)
	(footprint ""
		(layer "B.Cu")
		(at 417.6522 -74.0537)
		(property "Reference" "R9F3"
			(at 0 0 0)
			(layer "B.SilkS")
			(hide yes)
			(effects
				(font
					(size 1.27 1.27)
				)
				(justify mirror)
			)
		)
		(property "Value" ""
			(at 0 0 0)
			(layer "B.Fab")
			(effects
				(font
					(size 1.27 1.27)
				)
				(justify mirror)
			)
		)
		(duplicate_pad_numbers_are_jumpers no)
		(fp_poly
			(pts
				(xy 0.2794 -0.1016) (xy -0.2794 -0.1016) (xy -0.2794 0.9906) (xy 0.2794 0.9906)
			)
			(stroke
				(width 0)
				(type default)
			)
			(fill no)
			(layer "B.CrtYd")
		)
		(fp_line
			(start -0.2794 -0.1016)
			(end 0.2794 -0.1016)
			(stroke
				(width 0.1)
				(type default)
			)
			(layer "B.Fab")
		)
		(fp_line
			(start -0.2794 0.9906)
			(end -0.2794 -0.1016)
			(stroke
				(width 0.1)
				(type default)
			)
			(layer "B.Fab")
		)
		(fp_line
			(start 0.2794 -0.1016)
			(end 0.2794 0.9906)
			(stroke
				(width 0.1)
				(type default)
			)
			(layer "B.Fab")
		)
		(fp_line
			(start 0.2794 0.9906)
			(end -0.2794 0.9906)
			(stroke
				(width 0.1)
				(type default)
			)
			(layer "B.Fab")
		)
		(pad "1" smd rect
			(at 0 0 180)
			(size 0.508 0.508)
			(layers "B.Cu" "B.Mask" "B.Paste")
			(net "P3V3_STBY")
		)
		(pad "2" smd rect
			(at 0 0.889 180)
			(size 0.508 0.508)
			(layers "B.Cu" "B.Mask" "B.Paste")
			(net "FM_FAST_PROCHOT_EN")
		)
		(zone
			(layer "B.Cu")
			(hatch none 0.5)
			(connect_pads
				(clearance 0)
			)
			(min_thickness 0.25)
			(keepout
				(tracks allowed)
				(vias not_allowed)
				(pads allowed)
				(copperpour not_allowed)
				(footprints allowed)
			)
			(placement
				(enabled no)
				(sheetname "")
			)
			(fill
				(thermal_gap 0.5)
				(thermal_bridge_width 0.5)
				(island_removal_mode 0)
			)
			(polygon
				(pts
					(xy 417.9062 -73.7997) (xy 417.3982 -73.7997) (xy 417.3982 -73.4187) (xy 417.9062 -73.4187)
				)
			)
		)
		(zone
			(layer "B.Cu")
			(hatch none 0.5)
			(connect_pads
				(clearance 0)
			)
			(min_thickness 0.25)
			(keepout
				(tracks not_allowed)
				(vias allowed)
				(pads allowed)
				(copperpour not_allowed)
				(footprints allowed)
			)
			(placement
				(enabled no)
				(sheetname "")
			)
			(fill
				(thermal_gap 0.5)
				(thermal_bridge_width 0.5)
				(island_removal_mode 0)
			)
			(polygon
				(pts
					(xy 417.9062 -73.4187) (xy 417.3982 -73.4187) (xy 417.3982 -73.7997) (xy 417.9062 -73.7997)
				)
			)
		)
	)
	(footprint ""
		(layer "B.Cu")
		(at 375.158 -82.169 90)
		(property "Reference" "R7D18"
			(at 0.8382 -0.67818 90)
			(unlocked yes)
			(layer "B.SilkS")
			(effects
				(font
					(size 0.4064 0.254)
					(thickness 0.1524)
				)
				(justify left mirror)
			)
		)
		(property "Value" ""
			(at 0 0 90)
			(layer "B.Fab")
			(effects
				(font
					(size 1.27 1.27)
				)
				(justify mirror)
			)
		)
		(duplicate_pad_numbers_are_jumpers no)
		(fp_poly
			(pts
				(xy 0.2794 -0.1016) (xy -0.2794 -0.1016) (xy -0.2794 0.9906) (xy 0.2794 0.9906)
			)
			(stroke
				(width 0)
				(type default)
			)
			(fill no)
			(layer "B.CrtYd")
		)
		(fp_line
			(start 0.2794 -0.1016)
			(end 0.2794 0.9906)
			(stroke
				(width 0.1)
				(type default)
			)
			(layer "B.Fab")
		)
		(fp_line
			(start -0.2794 -0.1016)
			(end 0.2794 -0.1016)
			(stroke
				(width 0.1)
				(type default)
			)
			(layer "B.Fab")
		)
		(fp_line
			(start 0.2794 0.9906)
			(end -0.2794 0.9906)
			(stroke
				(width 0.1)
				(type default)
			)
			(layer "B.Fab")
		)
		(fp_line
			(start -0.2794 0.9906)
			(end -0.2794 -0.1016)
			(stroke
				(width 0.1)
				(type default)
			)
			(layer "B.Fab")
		)
		(pad "1" smd rect
			(at 0 0 270)
			(size 0.508 0.508)
			(layers "B.Cu" "B.Mask" "B.Paste")
			(net "FM_THERMTRIP_DLY")
		)
		(pad "2" smd rect
			(at 0 0.889 270)
			(size 0.508 0.508)
			(layers "B.Cu" "B.Mask" "B.Paste")
			(net "FM_THERMTRIP_DLY_R")
		)
		(zone
			(layer "B.Cu")
			(hatch none 0.5)
			(connect_pads
				(clearance 0)
			)
			(min_thickness 0.25)
			(keepout
				(tracks allowed)
				(vias not_allowed)
				(pads allowed)
				(copperpour not_allowed)
				(footprints allowed)
			)
			(placement
				(enabled no)
				(sheetname "")
			)
			(fill
				(thermal_gap 0.5)
				(thermal_bridge_width 0.5)
				(island_removal_mode 0)
			)
			(polygon
				(pts
					(xy 375.412 -82.423) (xy 375.412 -81.915) (xy 375.793 -81.915) (xy 375.793 -82.423)
				)
			)
		)
		(zone
			(layer "B.Cu")
			(hatch none 0.5)
			(connect_pads
				(clearance 0)
			)
			(min_thickness 0.25)
			(keepout
				(tracks not_allowed)
				(vias allowed)
				(pads allowed)
				(copperpour not_allowed)
				(footprints allowed)
			)
			(placement
				(enabled no)
				(sheetname "")
			)
			(fill
				(thermal_gap 0.5)
				(thermal_bridge_width 0.5)
				(island_removal_mode 0)
			)
			(polygon
				(pts
					(xy 375.793 -82.423) (xy 375.793 -81.915) (xy 375.412 -81.915) (xy 375.412 -82.423)
				)
			)
		)
	)
)
